# TIMECARD (Time Appliance Project (Time Card)) — schematic netlist excerpt (pin names and nets, part order shuffled) for the footprints in the layout excerpt that follows; sources: Cadence DE-HDL packaged netlist, KiCad conversion of R4006-B0001-02_R01.brd

R27  RESISTOR  33OHM 1%  pkg SMC_0402R_H016  page 16 : \1\ = PCIE_SMCLK ; \2\ = R_PCA9546_I2C_SCL
R188  RESISTOR  3.24KOHM 1%  pkg SMC_0402R_H014  page 30 : \1\ = SG ; \2\ = XP1R8V_FB

(kicad_pcb
	(version 20260206)
	(generator "pcbnew")
	(generator_version "10.0")
	(general
		(thickness 1.6)
		(legacy_teardrops no)
	)
	(paper "A4")
	(title_block
		(title "timecard-production-celestica-r4006 — R4006-B0001-02_R01.brd")
		(comment 1 "Time Appliance Project (Time Card) / footprints 835-836 of 1113")
	)
	(layers
		(0 "F.Cu" signal "TOP")
		(4 "In1.Cu" signal "L02_GND1")
		(6 "In2.Cu" signal "L03_SIG1")
		(8 "In3.Cu" signal "L04_GND2")
		(10 "In4.Cu" signal "L05_VCC1")
		(12 "In5.Cu" signal "L06_VCC2")
		(14 "In6.Cu" signal "L07_GND3")
		(16 "In7.Cu" signal "L08_SIG2")
		(18 "In8.Cu" signal "L09_GND4")
		(2 "B.Cu" signal "BOTTOM")
		(9 "F.Adhes" user "F.Adhesive")
		(11 "B.Adhes" user "B.Adhesive")
		(13 "F.Paste" user "Package Geometry/Pastemask Top")
		(15 "B.Paste" user "Package Geometry/Pastemask Bottom")
		(5 "F.SilkS" user "Ref Des/Silkscreen Top")
		(7 "B.SilkS" user "Ref Des/Silkscreen Bottom")
		(1 "F.Mask" user "Board Geometry/Soldermask Top")
		(3 "B.Mask" user "Board Geometry/Soldermask Bottom")
		(17 "Dwgs.User" user "User.Drawings")
		(19 "Cmts.User" user "User.Comments")
		(21 "Eco1.User" user "User.Eco1")
		(23 "Eco2.User" user "User.Eco2")
		(25 "Edge.Cuts" user "Board Geometry/Outline")
		(27 "Margin" user)
		(31 "F.CrtYd" user "Package Geometry/Place Bound Top")
		(29 "B.CrtYd" user "Package Geometry/Place Bound Bottom")
		(35 "F.Fab" user "Ref Des/Assembly Top")
		(33 "B.Fab" user "Ref Des/Assembly Bottom")
	)
	(footprint ""
		(layer "B.Cu")
		(at 20.955 -38.1)
		(property "Reference" "R27"
			(at 0.127 4.48437 0)
			(unlocked yes)
			(layer "B.SilkS")
			(effects
				(font
					(size 0.7874 0.5842)
					(thickness 0.1524)
				)
				(justify mirror)
			)
		)
		(property "Value" "VAL*"
			(at -0.02032 2.13233 0)
			(unlocked yes)
			(layer "B.Fab")
			(hide yes)
			(effects
				(font
					(size 0.7874 0.5842)
					(thickness 0.1524)
				)
				(justify mirror)
			)
		)
		(property "Device Type" "RESISTOR-G155-133R0-01,33OHM,1%"
			(at -0.008382 1.210564 0)
			(unlocked yes)
			(layer "B.Fab")
			(hide yes)
			(effects
				(font
					(size 0.7874 0.5842)
					(thickness 0.1524)
				)
				(justify mirror)
			)
		)
		(property "User Part Number" "PARTNUM*"
			(at -0.02032 4.024884 0)
			(unlocked yes)
			(layer "Cmts.User")
			(hide yes)
			(effects
				(font
					(size 0.7874 0.5842)
					(thickness 0.1524)
				)
				(justify mirror)
			)
		)
		(property "Tolerance" "TOL*"
			(at -0.044704 3.05435 0)
			(unlocked yes)
			(layer "Cmts.User")
			(hide yes)
			(effects
				(font
					(size 0.7874 0.5842)
					(thickness 0.1524)
				)
				(justify mirror)
			)
		)
		(duplicate_pad_numbers_are_jumpers no)
		(fp_line
			(start -1.143 -0.5588)
			(end 1.143 -0.5588)
			(stroke
				(width 0.1)
				(type default)
			)
			(layer "B.SilkS")
		)
		(fp_line
			(start -1.143 0.5588)
			(end -1.143 -0.5588)
			(stroke
				(width 0.1)
				(type default)
			)
			(layer "B.SilkS")
		)
		(fp_line
			(start 1.143 -0.5588)
			(end 1.143 0.5588)
			(stroke
				(width 0.1)
				(type default)
			)
			(layer "B.SilkS")
		)
		(fp_line
			(start 1.143 0.5588)
			(end -1.143 0.5588)
			(stroke
				(width 0.1)
				(type default)
			)
			(layer "B.SilkS")
		)
		(fp_rect
			(start 1.143 0.5588)
			(end -1.143 -0.5588)
			(stroke
				(width 0)
				(type default)
			)
			(fill no)
			(layer "B.CrtYd")
		)
		(fp_line
			(start -0.508 -0.3048)
			(end 0.508 -0.3048)
			(stroke
				(width 0.1)
				(type default)
			)
			(layer "B.Fab")
		)
		(fp_line
			(start -0.508 0.3048)
			(end -0.508 -0.3048)
			(stroke
				(width 0.1)
				(type default)
			)
			(layer "B.Fab")
		)
		(fp_line
			(start 0.508 -0.3048)
			(end 0.508 0.3048)
			(stroke
				(width 0.1)
				(type default)
			)
			(layer "B.Fab")
		)
		(fp_line
			(start 0.508 0.3048)
			(end -0.508 0.3048)
			(stroke
				(width 0.1)
				(type default)
			)
			(layer "B.Fab")
		)
		(pad "1" smd rect
			(at 0.5334 0 180)
			(size 0.7112 0.6096)
			(layers "B.Cu" "B.Mask" "B.Paste")
			(net "PCIE_SMCLK")
		)
		(pad "2" smd rect
			(at -0.5334 0 180)
			(size 0.7112 0.6096)
			(layers "B.Cu" "B.Mask" "B.Paste")
			(net "R_PCA9546_I2C_SCL")
		)
		(zone
			(layer "B.Cu")
			(hatch none 0.5)
			(connect_pads
				(clearance 0)
			)
			(min_thickness 0.25)
			(keepout
				(tracks allowed)
				(vias not_allowed)
				(pads allowed)
				(copperpour not_allowed)
				(footprints allowed)
			)
			(placement
				(enabled no)
				(sheetname "")
			)
			(fill
				(thermal_gap 0.5)
				(thermal_bridge_width 0.5)
				(island_removal_mode 0)
			)
			(polygon
				(pts
					(xy 21.0312 -37.7952) (xy 21.0312 -38.4048) (xy 20.8788 -38.4048) (xy 20.8788 -37.7952)
				)
			)
		)
	)
	(footprint ""
		(layer "B.Cu")
		(at 134.0612 -66.8528 -90)
		(property "Reference" "R188"
			(at 0.0508 1.89357 270)
			(unlocked yes)
			(layer "B.SilkS")
			(effects
				(font
					(size 0.7874 0.5842)
					(thickness 0.1524)
				)
				(justify mirror)
			)
		)
		(property "Value" "VAL*"
			(at -0.02032 2.13233 270)
			(unlocked yes)
			(layer "B.Fab")
			(hide yes)
			(effects
				(font
					(size 0.7874 0.5842)
					(thickness 0.1524)
				)
				(justify mirror)
			)
		)
		(property "Tolerance" "TOL*"
			(at -0.044704 3.05435 270)
			(unlocked yes)
			(layer "Cmts.User")
			(hide yes)
			(effects
				(font
					(size 0.7874 0.5842)
					(thickness 0.1524)
				)
				(justify mirror)
			)
		)
		(property "User Part Number" "PARTNUM*"
			(at -0.02032 4.024884 270)
			(unlocked yes)
			(layer "Cmts.User")
			(hide yes)
			(effects
				(font
					(size 0.7874 0.5842)
					(thickness 0.1524)
				)
				(justify mirror)
			)
		)
		(property "Device Type" "RESISTOR-G155-03241-01,3.24KOHA"
			(at -0.008382 1.210564 270)
			(unlocked yes)
			(layer "B.Fab")
			(hide yes)
			(effects
				(font
					(size 0.7874 0.5842)
					(thickness 0.1524)
				)
				(justify mirror)
			)
		)
		(duplicate_pad_numbers_are_jumpers no)
		(fp_line
			(start -1.143 0.5588)
			(end -1.143 -0.5588)
			(stroke
				(width 0.1)
				(type default)
			)
			(layer "B.SilkS")
		)
		(fp_line
			(start 1.143 0.5588)
			(end -1.143 0.5588)
			(stroke
				(width 0.1)
				(type default)
			)
			(layer "B.SilkS")
		)
		(fp_line
			(start -1.143 -0.5588)
			(end 1.143 -0.5588)
			(stroke
				(width 0.1)
				(type default)
			)
			(layer "B.SilkS")
		)
		(fp_line
			(start 1.143 -0.5588)
			(end 1.143 0.5588)
			(stroke
				(width 0.1)
				(type default)
			)
			(layer "B.SilkS")
		)
		(fp_rect
			(start -1.143 -0.5588)
			(end 1.143 0.5588)
			(stroke
				(width 0)
				(type default)
			)
			(fill no)
			(layer "B.CrtYd")
		)
		(fp_line
			(start -0.508 0.3048)
			(end -0.508 -0.3048)
			(stroke
				(width 0.1)
				(type default)
			)
			(layer "B.Fab")
		)
		(fp_line
			(start 0.508 0.3048)
			(end -0.508 0.3048)
			(stroke
				(width 0.1)
				(type default)
			)
			(layer "B.Fab")
		)
		(fp_line
			(start -0.508 -0.3048)
			(end 0.508 -0.3048)
			(stroke
				(width 0.1)
				(type default)
			)
			(layer "B.Fab")
		)
		(fp_line
			(start 0.508 -0.3048)
			(end 0.508 0.3048)
			(stroke
				(width 0.1)
				(type default)
			)
			(layer "B.Fab")
		)
		(pad "1" smd rect
			(at 0.5334 0 90)
			(size 0.7112 0.6096)
			(layers "B.Cu" "B.Mask" "B.Paste")
			(net "SG")
		)
		(pad "2" smd rect
			(at -0.5334 0 90)
			(size 0.7112 0.6096)
			(layers "B.Cu" "B.Mask" "B.Paste")
			(net "XP1R8V_FB")
		)
		(zone
			(layer "B.Cu")
			(hatch none 0.5)
			(connect_pads
				(clearance 0)
			)
			(min_thickness 0.25)
			(keepout
				(tracks allowed)
				(vias not_allowed)
				(pads allowed)
				(copperpour not_allowed)
				(footprints allowed)
			)
			(placement
				(enabled no)
				(sheetname "")
			)
			(fill
				(thermal_gap 0.5)
				(thermal_bridge_width 0.5)
				(island_removal_mode 0)
			)
			(polygon
				(pts
					(xy 134.366 -66.929) (xy 133.7564 -66.929) (xy 133.7564 -66.7766) (xy 134.366 -66.7766)
				)
			)
		)
	)
)
